(kicad_pcb
	(version 20260206)
	(generator "pcbnew")
	(generator_version "10.0")
	(general
		(thickness 1.6)
		(legacy_teardrops no)
	)
	(paper "A4")
	(title_block
		(title "01162023_DA0F0TEBIF0_F0T_Expander_BD_F_brd_V02_OCP.brd")
		(comment 1 "Grand Teton / footprints 7079-7085 of 9728")
	)
	(layers
		(0 "F.Cu" signal "TOP")
		(4 "In1.Cu" signal "GND")
		(6 "In2.Cu" signal "VCC")
		(8 "In3.Cu" signal "VCC1")
		(10 "In4.Cu" signal "GND1")
		(12 "In5.Cu" signal "IN1")
		(14 "In6.Cu" signal "GND2")
		(16 "In7.Cu" signal "IN2")
		(18 "In8.Cu" signal "GND3")
		(20 "In9.Cu" signal "IN3")
		(22 "In10.Cu" signal "GND4")
		(24 "In11.Cu" signal "IN4")
		(26 "In12.Cu" signal "GND5")
		(28 "In13.Cu" signal "IN5")
		(30 "In14.Cu" signal "GND6")
		(32 "In15.Cu" signal "IN6")
		(34 "In16.Cu" signal "GND7")
		(2 "B.Cu" signal "BOTTOM")
		(9 "F.Adhes" user "F.Adhesive")
		(11 "B.Adhes" user "B.Adhesive")
		(13 "F.Paste" user "Package Geometry/Pastemask Top")
		(15 "B.Paste" user "Package Geometry/Pastemask Bottom")
		(5 "F.SilkS" user "Ref Des/Silkscreen Top")
		(7 "B.SilkS" user "Ref Des/Silkscreen Bottom")
		(1 "F.Mask" user "Board Geometry/Soldermask Top")
		(3 "B.Mask" user "Board Geometry/Soldermask Bottom")
		(17 "Dwgs.User" user "User.Drawings")
		(19 "Cmts.User" user "User.Comments")
		(21 "Eco1.User" user "User.Eco1")
		(23 "Eco2.User" user "User.Eco2")
		(25 "Edge.Cuts" user "Board Geometry/Outline")
		(27 "Margin" user)
		(31 "F.CrtYd" user "Package Geometry/Place Bound Top")
		(29 "B.CrtYd" user "Package Geometry/Place Bound Bottom")
		(35 "F.Fab" user "Ref Des/Assembly Top")
		(33 "B.Fab" user "Ref Des/Assembly Bottom")
	)
	(footprint ""
		(layer "F.Cu")
		(at 49.656492 -20.467574 180)
		(property "Reference" "R1636"
			(at 0 0 180)
			(layer "F.SilkS")
			(hide yes)
			(effects
				(font
					(size 1.27 1.27)
				)
			)
		)
		(property "Value" ""
			(at 0 0 180)
			(layer "F.Fab")
			(effects
				(font
					(size 1.27 1.27)
				)
			)
		)
		(duplicate_pad_numbers_are_jumpers no)
		(fp_line
			(start 0.7874 0.4064)
			(end -0.7874 0.4064)
			(stroke
				(width 0.1524)
				(type default)
			)
			(layer "F.SilkS")
		)
		(fp_line
			(start 0.7874 -0.4064)
			(end 0.7874 0.4064)
			(stroke
				(width 0.1524)
				(type default)
			)
			(layer "F.SilkS")
		)
		(fp_line
			(start -0.7874 0.4064)
			(end -0.7874 -0.4064)
			(stroke
				(width 0.1524)
				(type default)
			)
			(layer "F.SilkS")
		)
		(fp_line
			(start -0.7874 -0.4064)
			(end 0.7874 -0.4064)
			(stroke
				(width 0.1524)
				(type default)
			)
			(layer "F.SilkS")
		)
		(fp_line
			(start 0.67945 0.3048)
			(end 0.120396 0.3048)
			(stroke
				(width 0.1)
				(type default)
			)
			(layer "F.Fab")
		)
		(fp_line
			(start 0.67945 -0.3048)
			(end 0.67945 0.3048)
			(stroke
				(width 0.1)
				(type default)
			)
			(layer "F.Fab")
		)
		(fp_line
			(start 0.12065 -0.2794)
			(end 0.12065 -0.3048)
			(stroke
				(width 0.1)
				(type default)
			)
			(layer "F.Fab")
		)
		(fp_line
			(start 0.12065 -0.3048)
			(end 0.67945 -0.3048)
			(stroke
				(width 0.1)
				(type default)
			)
			(layer "F.Fab")
		)
		(fp_line
			(start 0.120396 0.3048)
			(end 0.120396 0.2794)
			(stroke
				(width 0.1)
				(type default)
			)
			(layer "F.Fab")
		)
		(fp_line
			(start 0.120396 0.2794)
			(end -0.12065 0.2794)
			(stroke
				(width 0.1)
				(type default)
			)
			(layer "F.Fab")
		)
		(fp_line
			(start -0.12065 0.3048)
			(end -0.67945 0.3048)
			(stroke
				(width 0.1)
				(type default)
			)
			(layer "F.Fab")
		)
		(fp_line
			(start -0.12065 0.2794)
			(end -0.12065 0.3048)
			(stroke
				(width 0.1)
				(type default)
			)
			(layer "F.Fab")
		)
		(fp_line
			(start -0.12065 -0.2794)
			(end 0.12065 -0.2794)
			(stroke
				(width 0.1)
				(type default)
			)
			(layer "F.Fab")
		)
		(fp_line
			(start -0.12065 -0.305054)
			(end -0.12065 -0.2794)
			(stroke
				(width 0.1)
				(type default)
			)
			(layer "F.Fab")
		)
		(fp_line
			(start -0.67945 0.3048)
			(end -0.67945 -0.305054)
			(stroke
				(width 0.1)
				(type default)
			)
			(layer "F.Fab")
		)
		(fp_line
			(start -0.67945 -0.305054)
			(end -0.12065 -0.305054)
			(stroke
				(width 0.1)
				(type default)
			)
			(layer "F.Fab")
		)
		(pad "1" smd circle
			(at -0.40005 0 180)
			(size 0 0)
			(layers "F.Cu" "F.Mask" "F.Paste")
			(net "P3V3_SSD1")
		)
		(pad "2" smd circle
			(at 0.40005 0 180)
			(size 0 0)
			(layers "F.Cu" "F.Mask" "F.Paste")
			(net "SMB_ISO_SSD1_SDA")
		)
	)
	(footprint ""
		(layer "F.Cu")
		(at 258.54533 -196.081396)
		(property "Reference" "R2619"
			(at 0 0 0)
			(layer "F.SilkS")
			(hide yes)
			(effects
				(font
					(size 1.27 1.27)
				)
			)
		)
		(property "Value" ""
			(at 0 0 0)
			(layer "F.Fab")
			(effects
				(font
					(size 1.27 1.27)
				)
			)
		)
		(duplicate_pad_numbers_are_jumpers no)
		(fp_line
			(start -0.7874 -0.4064)
			(end 0.7874 -0.4064)
			(stroke
				(width 0.1524)
				(type default)
			)
			(layer "F.SilkS")
		)
		(fp_line
			(start -0.7874 0.4064)
			(end -0.7874 -0.4064)
			(stroke
				(width 0.1524)
				(type default)
			)
			(layer "F.SilkS")
		)
		(fp_line
			(start 0.7874 -0.4064)
			(end 0.7874 0.4064)
			(stroke
				(width 0.1524)
				(type default)
			)
			(layer "F.SilkS")
		)
		(fp_line
			(start 0.7874 0.4064)
			(end -0.7874 0.4064)
			(stroke
				(width 0.1524)
				(type default)
			)
			(layer "F.SilkS")
		)
		(fp_line
			(start -0.67945 -0.305054)
			(end -0.12065 -0.305054)
			(stroke
				(width 0.1)
				(type default)
			)
			(layer "F.Fab")
		)
		(fp_line
			(start -0.67945 0.3048)
			(end -0.67945 -0.305054)
			(stroke
				(width 0.1)
				(type default)
			)
			(layer "F.Fab")
		)
		(fp_line
			(start -0.12065 -0.305054)
			(end -0.12065 -0.2794)
			(stroke
				(width 0.1)
				(type default)
			)
			(layer "F.Fab")
		)
		(fp_line
			(start -0.12065 -0.2794)
			(end 0.12065 -0.2794)
			(stroke
				(width 0.1)
				(type default)
			)
			(layer "F.Fab")
		)
		(fp_line
			(start -0.12065 0.2794)
			(end -0.12065 0.3048)
			(stroke
				(width 0.1)
				(type default)
			)
			(layer "F.Fab")
		)
		(fp_line
			(start -0.12065 0.3048)
			(end -0.67945 0.3048)
			(stroke
				(width 0.1)
				(type default)
			)
			(layer "F.Fab")
		)
		(fp_line
			(start 0.120396 0.2794)
			(end -0.12065 0.2794)
			(stroke
				(width 0.1)
				(type default)
			)
			(layer "F.Fab")
		)
		(fp_line
			(start 0.120396 0.3048)
			(end 0.120396 0.2794)
			(stroke
				(width 0.1)
				(type default)
			)
			(layer "F.Fab")
		)
		(fp_line
			(start 0.12065 -0.3048)
			(end 0.67945 -0.3048)
			(stroke
				(width 0.1)
				(type default)
			)
			(layer "F.Fab")
		)
		(fp_line
			(start 0.12065 -0.2794)
			(end 0.12065 -0.3048)
			(stroke
				(width 0.1)
				(type default)
			)
			(layer "F.Fab")
		)
		(fp_line
			(start 0.67945 -0.3048)
			(end 0.67945 0.3048)
			(stroke
				(width 0.1)
				(type default)
			)
			(layer "F.Fab")
		)
		(fp_line
			(start 0.67945 0.3048)
			(end 0.120396 0.3048)
			(stroke
				(width 0.1)
				(type default)
			)
			(layer "F.Fab")
		)
		(pad "1" smd circle
			(at -0.40005 0)
			(size 0 0)
			(layers "F.Cu" "F.Mask" "F.Paste")
			(net "JTAG_FPGA_TMS")
		)
		(pad "2" smd circle
			(at 0.40005 0)
			(size 0 0)
			(layers "F.Cu" "F.Mask" "F.Paste")
			(net "GND")
		)
	)
	(footprint ""
		(layer "F.Cu")
		(at 216.567512 -231.416606 90)
		(property "Reference" "R4552"
			(at 0 0 90)
			(layer "F.SilkS")
			(hide yes)
			(effects
				(font
					(size 1.27 1.27)
				)
			)
		)
		(property "Value" ""
			(at 0 0 90)
			(layer "F.Fab")
			(effects
				(font
					(size 1.27 1.27)
				)
			)
		)
		(duplicate_pad_numbers_are_jumpers no)
		(fp_line
			(start 0.7874 -0.4064)
			(end 0.7874 0.4064)
			(stroke
				(width 0.1524)
				(type default)
			)
			(layer "F.SilkS")
		)
		(fp_line
			(start -0.7874 -0.4064)
			(end 0.7874 -0.4064)
			(stroke
				(width 0.1524)
				(type default)
			)
			(layer "F.SilkS")
		)
		(fp_line
			(start 0.7874 0.4064)
			(end -0.7874 0.4064)
			(stroke
				(width 0.1524)
				(type default)
			)
			(layer "F.SilkS")
		)
		(fp_line
			(start -0.7874 0.4064)
			(end -0.7874 -0.4064)
			(stroke
				(width 0.1524)
				(type default)
			)
			(layer "F.SilkS")
		)
		(fp_line
			(start -0.12065 -0.305054)
			(end -0.12065 -0.2794)
			(stroke
				(width 0.1)
				(type default)
			)
			(layer "F.Fab")
		)
		(fp_line
			(start -0.67945 -0.305054)
			(end -0.12065 -0.305054)
			(stroke
				(width 0.1)
				(type default)
			)
			(layer "F.Fab")
		)
		(fp_line
			(start 0.67945 -0.3048)
			(end 0.67945 0.3048)
			(stroke
				(width 0.1)
				(type default)
			)
			(layer "F.Fab")
		)
		(fp_line
			(start 0.12065 -0.3048)
			(end 0.67945 -0.3048)
			(stroke
				(width 0.1)
				(type default)
			)
			(layer "F.Fab")
		)
		(fp_line
			(start 0.12065 -0.2794)
			(end 0.12065 -0.3048)
			(stroke
				(width 0.1)
				(type default)
			)
			(layer "F.Fab")
		)
		(fp_line
			(start -0.12065 -0.2794)
			(end 0.12065 -0.2794)
			(stroke
				(width 0.1)
				(type default)
			)
			(layer "F.Fab")
		)
		(fp_line
			(start 0.120396 0.2794)
			(end -0.12065 0.2794)
			(stroke
				(width 0.1)
				(type default)
			)
			(layer "F.Fab")
		)
		(fp_line
			(start -0.12065 0.2794)
			(end -0.12065 0.3048)
			(stroke
				(width 0.1)
				(type default)
			)
			(layer "F.Fab")
		)
		(fp_line
			(start 0.67945 0.3048)
			(end 0.120396 0.3048)
			(stroke
				(width 0.1)
				(type default)
			)
			(layer "F.Fab")
		)
		(fp_line
			(start 0.120396 0.3048)
			(end 0.120396 0.2794)
			(stroke
				(width 0.1)
				(type default)
			)
			(layer "F.Fab")
		)
		(fp_line
			(start -0.12065 0.3048)
			(end -0.67945 0.3048)
			(stroke
				(width 0.1)
				(type default)
			)
			(layer "F.Fab")
		)
		(fp_line
			(start -0.67945 0.3048)
			(end -0.67945 -0.305054)
			(stroke
				(width 0.1)
				(type default)
			)
			(layer "F.Fab")
		)
		(pad "1" smd circle
			(at -0.40005 0 90)
			(size 0 0)
			(layers "F.Cu" "F.Mask" "F.Paste")
			(net "BOARD_ID2")
		)
		(pad "2" smd circle
			(at 0.40005 0 90)
			(size 0 0)
			(layers "F.Cu" "F.Mask" "F.Paste")
			(net "P3V3_AUX")
		)
	)
	(footprint ""
		(layer "F.Cu")
		(at 11.593322 -119.105426 -90)
		(property "Reference" "R5856"
			(at 0 0 270)
			(layer "F.SilkS")
			(hide yes)
			(effects
				(font
					(size 1.27 1.27)
				)
			)
		)
		(property "Value" ""
			(at 0 0 270)
			(layer "F.Fab")
			(effects
				(font
					(size 1.27 1.27)
				)
			)
		)
		(duplicate_pad_numbers_are_jumpers no)
		(fp_line
			(start -0.7874 0.4064)
			(end -0.7874 -0.4064)
			(stroke
				(width 0.1524)
				(type default)
			)
			(layer "F.SilkS")
		)
		(fp_line
			(start 0.7874 0.4064)
			(end -0.7874 0.4064)
			(stroke
				(width 0.1524)
				(type default)
			)
			(layer "F.SilkS")
		)
		(fp_line
			(start -0.7874 -0.4064)
			(end 0.7874 -0.4064)
			(stroke
				(width 0.1524)
				(type default)
			)
			(layer "F.SilkS")
		)
		(fp_line
			(start 0.7874 -0.4064)
			(end 0.7874 0.4064)
			(stroke
				(width 0.1524)
				(type default)
			)
			(layer "F.SilkS")
		)
		(fp_line
			(start -0.67945 0.3048)
			(end -0.67945 -0.305054)
			(stroke
				(width 0.1)
				(type default)
			)
			(layer "F.Fab")
		)
		(fp_line
			(start -0.12065 0.3048)
			(end -0.67945 0.3048)
			(stroke
				(width 0.1)
				(type default)
			)
			(layer "F.Fab")
		)
		(fp_line
			(start 0.120396 0.3048)
			(end 0.120396 0.2794)
			(stroke
				(width 0.1)
				(type default)
			)
			(layer "F.Fab")
		)
		(fp_line
			(start 0.67945 0.3048)
			(end 0.120396 0.3048)
			(stroke
				(width 0.1)
				(type default)
			)
			(layer "F.Fab")
		)
		(fp_line
			(start -0.12065 0.2794)
			(end -0.12065 0.3048)
			(stroke
				(width 0.1)
				(type default)
			)
			(layer "F.Fab")
		)
		(fp_line
			(start 0.120396 0.2794)
			(end -0.12065 0.2794)
			(stroke
				(width 0.1)
				(type default)
			)
			(layer "F.Fab")
		)
		(fp_line
			(start -0.12065 -0.2794)
			(end 0.12065 -0.2794)
			(stroke
				(width 0.1)
				(type default)
			)
			(layer "F.Fab")
		)
		(fp_line
			(start 0.12065 -0.2794)
			(end 0.12065 -0.3048)
			(stroke
				(width 0.1)
				(type default)
			)
			(layer "F.Fab")
		)
		(fp_line
			(start 0.12065 -0.3048)
			(end 0.67945 -0.3048)
			(stroke
				(width 0.1)
				(type default)
			)
			(layer "F.Fab")
		)
		(fp_line
			(start 0.67945 -0.3048)
			(end 0.67945 0.3048)
			(stroke
				(width 0.1)
				(type default)
			)
			(layer "F.Fab")
		)
		(fp_line
			(start -0.67945 -0.305054)
			(end -0.12065 -0.305054)
			(stroke
				(width 0.1)
				(type default)
			)
			(layer "F.Fab")
		)
		(fp_line
			(start -0.12065 -0.305054)
			(end -0.12065 -0.2794)
			(stroke
				(width 0.1)
				(type default)
			)
			(layer "F.Fab")
		)
		(pad "1" smd circle
			(at -0.40005 0 270)
			(size 0 0)
			(layers "F.Cu" "F.Mask" "F.Paste")
			(net "P3V3_AUX")
		)
		(pad "2" smd circle
			(at 0.40005 0 270)
			(size 0 0)
			(layers "F.Cu" "F.Mask" "F.Paste")
			(net "PWRGD_P3V3_NIC0_D")
		)
	)
	(footprint ""
		(layer "F.Cu")
		(at 436.95239 -114.384836 180)
		(property "Reference" "PC917"
			(at 0 0 180)
			(layer "F.SilkS")
			(hide yes)
			(effects
				(font
					(size 1.27 1.27)
				)
			)
		)
		(property "Value" ""
			(at 0 0 180)
			(layer "F.Fab")
			(effects
				(font
					(size 1.27 1.27)
				)
			)
		)
		(duplicate_pad_numbers_are_jumpers no)
		(fp_line
			(start 0.7874 0.4064)
			(end -0.7874 0.4064)
			(stroke
				(width 0.1524)
				(type default)
			)
			(layer "F.SilkS")
		)
		(fp_line
			(start 0.7874 -0.4064)
			(end 0.7874 0.4064)
			(stroke
				(width 0.1524)
				(type default)
			)
			(layer "F.SilkS")
		)
		(fp_line
			(start -0.7874 0.4064)
			(end -0.7874 -0.4064)
			(stroke
				(width 0.1524)
				(type default)
			)
			(layer "F.SilkS")
		)
		(fp_line
			(start -0.7874 -0.4064)
			(end 0.7874 -0.4064)
			(stroke
				(width 0.1524)
				(type default)
			)
			(layer "F.SilkS")
		)
		(fp_line
			(start 0.67945 0.3048)
			(end 0.120396 0.3048)
			(stroke
				(width 0.1)
				(type default)
			)
			(layer "F.Fab")
		)
		(fp_line
			(start 0.67945 -0.3048)
			(end 0.67945 0.3048)
			(stroke
				(width 0.1)
				(type default)
			)
			(layer "F.Fab")
		)
		(fp_line
			(start 0.12065 -0.2794)
			(end 0.12065 -0.3048)
			(stroke
				(width 0.1)
				(type default)
			)
			(layer "F.Fab")
		)
		(fp_line
			(start 0.12065 -0.3048)
			(end 0.67945 -0.3048)
			(stroke
				(width 0.1)
				(type default)
			)
			(layer "F.Fab")
		)
		(fp_line
			(start 0.120396 0.3048)
			(end 0.120396 0.2794)
			(stroke
				(width 0.1)
				(type default)
			)
			(layer "F.Fab")
		)
		(fp_line
			(start 0.120396 0.2794)
			(end -0.12065 0.2794)
			(stroke
				(width 0.1)
				(type default)
			)
			(layer "F.Fab")
		)
		(fp_line
			(start -0.12065 0.3048)
			(end -0.67945 0.3048)
			(stroke
				(width 0.1)
				(type default)
			)
			(layer "F.Fab")
		)
		(fp_line
			(start -0.12065 0.2794)
			(end -0.12065 0.3048)
			(stroke
				(width 0.1)
				(type default)
			)
			(layer "F.Fab")
		)
		(fp_line
			(start -0.12065 -0.2794)
			(end 0.12065 -0.2794)
			(stroke
				(width 0.1)
				(type default)
			)
			(layer "F.Fab")
		)
		(fp_line
			(start -0.12065 -0.305054)
			(end -0.12065 -0.2794)
			(stroke
				(width 0.1)
				(type default)
			)
			(layer "F.Fab")
		)
		(fp_line
			(start -0.67945 0.3048)
			(end -0.67945 -0.305054)
			(stroke
				(width 0.1)
				(type default)
			)
			(layer "F.Fab")
		)
		(fp_line
			(start -0.67945 -0.305054)
			(end -0.12065 -0.305054)
			(stroke
				(width 0.1)
				(type default)
			)
			(layer "F.Fab")
		)
		(pad "1" smd circle
			(at -0.40005 0 180)
			(size 0 0)
			(layers "F.Cu" "F.Mask" "F.Paste")
			(net "P3V3_NIC7_CO_DV_DT")
		)
		(pad "2" smd circle
			(at 0.40005 0 180)
			(size 0 0)
			(layers "F.Cu" "F.Mask" "F.Paste")
			(net "GND")
		)
	)
	(footprint ""
		(layer "F.Cu")
		(at 244.588792 -284.252162)
		(property "Reference" "PC259"
			(at 0 0 0)
			(layer "F.SilkS")
			(hide yes)
			(effects
				(font
					(size 1.27 1.27)
				)
			)
		)
		(property "Value" ""
			(at 0 0 0)
			(layer "F.Fab")
			(effects
				(font
					(size 1.27 1.27)
				)
			)
		)
		(duplicate_pad_numbers_are_jumpers no)
		(fp_line
			(start -2.750058 -1.988058)
			(end -2.750058 -0.9398)
			(stroke
				(width 0.1524)
				(type default)
			)
			(layer "F.SilkS")
		)
		(fp_line
			(start -2.750058 0.9398)
			(end -2.750058 1.988058)
			(stroke
				(width 0.1524)
				(type default)
			)
			(layer "F.SilkS")
		)
		(fp_line
			(start -2.750058 1.988058)
			(end -1.988058 2.750058)
			(stroke
				(width 0.1524)
				(type default)
			)
			(layer "F.SilkS")
		)
		(fp_line
			(start -1.988058 -2.750058)
			(end -2.750058 -1.988058)
			(stroke
				(width 0.1524)
				(type default)
			)
			(layer "F.SilkS")
		)
		(fp_line
			(start -1.988058 2.750058)
			(end 2.750058 2.750058)
			(stroke
				(width 0.1524)
				(type default)
			)
			(layer "F.SilkS")
		)
		(fp_line
			(start 2.750058 -2.750058)
			(end -1.988058 -2.750058)
			(stroke
				(width 0.1524)
				(type default)
			)
			(layer "F.SilkS")
		)
		(fp_line
			(start 2.750058 -0.9398)
			(end 2.750058 -2.750058)
			(stroke
				(width 0.1524)
				(type default)
			)
			(layer "F.SilkS")
		)
		(fp_line
			(start 2.750058 2.750058)
			(end 2.750058 0.9398)
			(stroke
				(width 0.1524)
				(type default)
			)
			(layer "F.SilkS")
		)
		(fp_line
			(start -2.750058 -2.750058)
			(end -2.750058 2.750058)
			(stroke
				(width 0.1)
				(type default)
			)
			(layer "F.Fab")
		)
		(fp_line
			(start -2.750058 2.750058)
			(end 2.750058 2.750058)
			(stroke
				(width 0.1)
				(type default)
			)
			(layer "F.Fab")
		)
		(fp_line
			(start 2.750058 -2.750058)
			(end -2.750058 -2.750058)
			(stroke
				(width 0.1)
				(type default)
			)
			(layer "F.Fab")
		)
		(fp_line
			(start 2.750058 2.750058)
			(end 2.750058 -2.750058)
			(stroke
				(width 0.1)
				(type default)
			)
			(layer "F.Fab")
		)
		(pad "1" smd rect
			(at -2.199894 0 90)
			(size 1.6002 3.0226)
			(layers "F.Cu" "F.Mask" "F.Paste")
			(net "P1V25_PEX2_R")
		)
		(pad "2" smd rect
			(at 2.199894 0 90)
			(size 1.6002 3.0226)
			(layers "F.Cu" "F.Mask" "F.Paste")
			(net "GND")
		)
	)
	(footprint ""
		(layer "F.Cu")
		(at 484.9495 -548.246554 180)
		(property "Reference" "SCREW_SSD3_2"
			(at -5.207 -1.402334 0)
			(unlocked yes)
			(layer "B.SilkS")
			(effects
				(font
					(size 0.7874 0.5842)
					(thickness 0.1524)
				)
				(justify mirror)
			)
		)
		(property "Value" ""
			(at 0 0 180)
			(layer "F.Fab")
			(effects
				(font
					(size 1.27 1.27)
				)
			)
		)
		(duplicate_pad_numbers_are_jumpers no)
		(pad "1" thru_hole circle
			(at 0 0 180)
			(size 0.4572 0.4572)
			(drill 0.2032)
			(layers "*.Cu" "*.Mask")
			(remove_unused_layers no)
			(net "Net_9137")
			(clearance 0.127)
			(thermal_gap 0.127)
			(padstack
				(mode front_inner_back)
				(layer "Inner"
					(shape circle)
					(size 0.4572 0.4572)
					(clearance 0.127)
				)
				(layer "B.Cu"
					(shape circle)
					(size 0.508 0.508)
					(clearance 0.1016)
				)
			)
		)
	)
)
